(kicad_pcb
	(version 20260206)
	(generator "pcbnew")
	(generator_version "10.0")
	(general
		(thickness 1.6)
		(legacy_teardrops no)
	)
	(paper "A4")
	(title_block
		(title "9054_F0T_PDB_BD_GPU_F_V04_1213_1550_OCP.brd")
		(comment 1 "Grand Teton / footprints 347-353 of 608")
	)
	(layers
		(0 "F.Cu" signal "TOP")
		(4 "In1.Cu" signal "GND")
		(6 "In2.Cu" signal "IN1")
		(8 "In3.Cu" signal "GND1")
		(10 "In4.Cu" signal "VCC")
		(12 "In5.Cu" signal "VCC1")
		(14 "In6.Cu" signal "GND2")
		(16 "In7.Cu" signal "IN2")
		(18 "In8.Cu" signal "GND3")
		(2 "B.Cu" signal "BOTTOM")
		(9 "F.Adhes" user "F.Adhesive")
		(11 "B.Adhes" user "B.Adhesive")
		(13 "F.Paste" user "Package Geometry/Pastemask Top")
		(15 "B.Paste" user "Package Geometry/Pastemask Bottom")
		(5 "F.SilkS" user "Ref Des/Silkscreen Top")
		(7 "B.SilkS" user "Ref Des/Silkscreen Bottom")
		(1 "F.Mask" user "Board Geometry/Soldermask Top")
		(3 "B.Mask" user "Board Geometry/Soldermask Bottom")
		(17 "Dwgs.User" user "User.Drawings")
		(19 "Cmts.User" user "User.Comments")
		(21 "Eco1.User" user "User.Eco1")
		(23 "Eco2.User" user "User.Eco2")
		(25 "Edge.Cuts" user "Board Geometry/Outline")
		(27 "Margin" user)
		(31 "F.CrtYd" user "Package Geometry/Place Bound Top")
		(29 "B.CrtYd" user "Package Geometry/Place Bound Bottom")
		(35 "F.Fab" user "Ref Des/Assembly Top")
		(33 "B.Fab" user "Ref Des/Assembly Bottom")
	)
	(footprint ""
		(layer "F.Cu")
		(at 416.948874 -55.831232)
		(property "Reference" ""
			(at 0 0 0)
			(layer "F.SilkS")
			(hide yes)
			(effects
				(font
					(size 1.27 1.27)
				)
			)
		)
		(property "Value" ""
			(at 0 0 0)
			(layer "F.Fab")
			(effects
				(font
					(size 1.27 1.27)
				)
			)
		)
		(duplicate_pad_numbers_are_jumpers no)
		(pad "1" smd circle
			(at 0 0)
			(size 0.9906 0.9906)
			(layers "F.Cu" "F.Mask" "F.Paste")
			(net "Net_246")
		)
		(zone
			(layer "F.Cu")
			(hatch none 0.5)
			(connect_pads
				(clearance 0)
			)
			(min_thickness 0.25)
			(keepout
				(tracks not_allowed)
				(vias allowed)
				(pads allowed)
				(copperpour not_allowed)
				(footprints allowed)
			)
			(placement
				(enabled no)
				(sheetname "")
			)
			(fill
				(thermal_gap 0.5)
				(thermal_bridge_width 0.5)
				(island_removal_mode 0)
			)
			(polygon
				(pts
					(arc
						(start 418.574474 -55.831232)
						(mid 415.323274 -55.831232)
						(end 418.574474 -55.831232)
					)
				)
			)
		)
	)
	(footprint ""
		(layer "F.Cu")
		(at 437.134 -41.148 90)
		(property "Reference" "R6"
			(at 0 0 90)
			(layer "F.SilkS")
			(hide yes)
			(effects
				(font
					(size 1.27 1.27)
				)
			)
		)
		(property "Value" ""
			(at 0 0 90)
			(layer "F.Fab")
			(effects
				(font
					(size 1.27 1.27)
				)
			)
		)
		(duplicate_pad_numbers_are_jumpers no)
		(fp_line
			(start 0.7874 -0.4064)
			(end 0.7874 0.4064)
			(stroke
				(width 0.1524)
				(type default)
			)
			(layer "F.SilkS")
		)
		(fp_line
			(start -0.7874 -0.4064)
			(end 0.7874 -0.4064)
			(stroke
				(width 0.1524)
				(type default)
			)
			(layer "F.SilkS")
		)
		(fp_line
			(start 0.7874 0.4064)
			(end -0.7874 0.4064)
			(stroke
				(width 0.1524)
				(type default)
			)
			(layer "F.SilkS")
		)
		(fp_line
			(start -0.7874 0.4064)
			(end -0.7874 -0.4064)
			(stroke
				(width 0.1524)
				(type default)
			)
			(layer "F.SilkS")
		)
		(fp_line
			(start -0.12065 -0.305054)
			(end -0.12065 -0.2794)
			(stroke
				(width 0.1)
				(type default)
			)
			(layer "F.Fab")
		)
		(fp_line
			(start -0.67945 -0.305054)
			(end -0.12065 -0.305054)
			(stroke
				(width 0.1)
				(type default)
			)
			(layer "F.Fab")
		)
		(fp_line
			(start 0.67945 -0.3048)
			(end 0.67945 0.3048)
			(stroke
				(width 0.1)
				(type default)
			)
			(layer "F.Fab")
		)
		(fp_line
			(start 0.12065 -0.3048)
			(end 0.67945 -0.3048)
			(stroke
				(width 0.1)
				(type default)
			)
			(layer "F.Fab")
		)
		(fp_line
			(start 0.12065 -0.2794)
			(end 0.12065 -0.3048)
			(stroke
				(width 0.1)
				(type default)
			)
			(layer "F.Fab")
		)
		(fp_line
			(start -0.12065 -0.2794)
			(end 0.12065 -0.2794)
			(stroke
				(width 0.1)
				(type default)
			)
			(layer "F.Fab")
		)
		(fp_line
			(start 0.120396 0.2794)
			(end -0.12065 0.2794)
			(stroke
				(width 0.1)
				(type default)
			)
			(layer "F.Fab")
		)
		(fp_line
			(start -0.12065 0.2794)
			(end -0.12065 0.3048)
			(stroke
				(width 0.1)
				(type default)
			)
			(layer "F.Fab")
		)
		(fp_line
			(start 0.67945 0.3048)
			(end 0.120396 0.3048)
			(stroke
				(width 0.1)
				(type default)
			)
			(layer "F.Fab")
		)
		(fp_line
			(start 0.120396 0.3048)
			(end 0.120396 0.2794)
			(stroke
				(width 0.1)
				(type default)
			)
			(layer "F.Fab")
		)
		(fp_line
			(start -0.12065 0.3048)
			(end -0.67945 0.3048)
			(stroke
				(width 0.1)
				(type default)
			)
			(layer "F.Fab")
		)
		(fp_line
			(start -0.67945 0.3048)
			(end -0.67945 -0.305054)
			(stroke
				(width 0.1)
				(type default)
			)
			(layer "F.Fab")
		)
		(pad "1" smd circle
			(at -0.40005 0 90)
			(size 0 0)
			(layers "F.Cu" "F.Mask" "F.Paste")
			(net "SMB_PDB_SCL")
		)
		(pad "2" smd circle
			(at 0.40005 0 90)
			(size 0 0)
			(layers "F.Cu" "F.Mask" "F.Paste")
			(net "SMB_PDB_MISC_SCL_R")
		)
	)
	(footprint ""
		(layer "F.Cu")
		(at 220.0656 -97.0788)
		(property "Reference" "JP3"
			(at 1.0414 -1.95453 0)
			(unlocked yes)
			(layer "F.SilkS")
			(effects
				(font
					(size 0.7874 0.5842)
					(thickness 0.1524)
				)
				(justify left)
			)
		)
		(property "Value" ""
			(at 0 0 0)
			(layer "F.Fab")
			(effects
				(font
					(size 1.27 1.27)
				)
			)
		)
		(duplicate_pad_numbers_are_jumpers no)
		(fp_line
			(start -1.234948 -1.335024)
			(end 1.234948 -1.335024)
			(stroke
				(width 0.1524)
				(type default)
			)
			(layer "F.SilkS")
		)
		(fp_line
			(start -1.234948 6.415024)
			(end -1.234948 -1.335024)
			(stroke
				(width 0.1524)
				(type default)
			)
			(layer "F.SilkS")
		)
		(fp_line
			(start 1.234948 -1.335024)
			(end 1.234948 6.415024)
			(stroke
				(width 0.1524)
				(type default)
			)
			(layer "F.SilkS")
		)
		(fp_line
			(start 1.234948 6.415024)
			(end -1.234948 6.415024)
			(stroke
				(width 0.1524)
				(type default)
			)
			(layer "F.SilkS")
		)
		(fp_poly
			(pts
				(xy 0.508 -2.530348) (xy -0.508 -2.530348) (xy 0 -1.514348)
			)
			(stroke
				(width 0)
				(type default)
			)
			(fill yes)
			(layer "F.SilkS")
		)
		(fp_line
			(start -1.234948 -1.335024)
			(end 1.234948 -1.335024)
			(stroke
				(width 0.1)
				(type default)
			)
			(layer "F.Fab")
		)
		(fp_line
			(start -1.234948 6.415024)
			(end -1.234948 -1.335024)
			(stroke
				(width 0.1)
				(type default)
			)
			(layer "F.Fab")
		)
		(fp_line
			(start 1.234948 -1.335024)
			(end 1.234948 6.415024)
			(stroke
				(width 0.1)
				(type default)
			)
			(layer "F.Fab")
		)
		(fp_line
			(start 1.234948 6.415024)
			(end -1.234948 6.415024)
			(stroke
				(width 0.1)
				(type default)
			)
			(layer "F.Fab")
		)
		(fp_poly
			(pts
				(xy 0.508 -2.530348) (xy -0.508 -2.530348) (xy 0 -1.514348)
			)
			(stroke
				(width 0)
				(type default)
			)
			(fill yes)
			(layer "F.Fab")
		)
		(fp_text user "3"
			(at -0.3683 7.45617 0)
			(unlocked yes)
			(layer "F.SilkS")
			(effects
				(font
					(size 0.7874 0.5842)
					(thickness 0.1524)
				)
				(justify left)
			)
		)
		(fp_text user "1"
			(at -0.00127 -0.954024 270)
			(unlocked yes)
			(layer "B.SilkS")
			(effects
				(font
					(size 0.7874 0.5842)
					(thickness 0.1524)
				)
				(justify left mirror)
			)
		)
		(fp_text user "3"
			(at -0.00127 6.640576 270)
			(unlocked yes)
			(layer "B.SilkS")
			(effects
				(font
					(size 0.7874 0.5842)
					(thickness 0.1524)
				)
				(justify left mirror)
			)
		)
		(fp_text user "1"
			(at -0.00127 -0.954024 270)
			(unlocked yes)
			(layer "B.Fab")
			(effects
				(font
					(size 0.7874 0.5842)
					(thickness 0.1524)
				)
				(justify left mirror)
			)
		)
		(fp_text user "3"
			(at -0.00127 6.640576 270)
			(unlocked yes)
			(layer "B.Fab")
			(effects
				(font
					(size 0.7874 0.5842)
					(thickness 0.1524)
				)
				(justify left mirror)
			)
		)
		(fp_text user "3"
			(at -0.009652 6.5659 270)
			(unlocked yes)
			(layer "F.Fab")
			(effects
				(font
					(size 0.7874 0.5842)
					(thickness 0.1524)
				)
				(justify left)
			)
		)
		(pad "1" thru_hole rect
			(at 0 0 270)
			(size 1.6764 1.6764)
			(drill 1.1684)
			(layers "*.Cu" "*.Mask")
			(remove_unused_layers no)
			(net "SMB_P52V_PDB_DEBUG_SDA")
			(clearance 0)
			(padstack
				(mode front_inner_back)
				(layer "Inner"
					(shape circle)
					(size 1.6764 1.6764)
					(clearance 0)
				)
				(layer "B.Cu"
					(shape rect)
					(size 1.6764 1.6764)
					(clearance 0)
				)
			)
		)
		(pad "2" thru_hole circle
			(at 0 2.54 270)
			(size 1.6764 1.6764)
			(drill 1.1684)
			(layers "*.Cu" "*.Mask")
			(remove_unused_layers no)
			(net "GND")
			(clearance 0)
		)
		(pad "3" thru_hole circle
			(at 0 5.08 270)
			(size 1.6764 1.6764)
			(drill 1.1684)
			(layers "*.Cu" "*.Mask")
			(remove_unused_layers no)
			(net "SMB_P52V_PDB_DEBUG_SCL")
			(clearance 0)
		)
	)
	(footprint ""
		(layer "F.Cu")
		(at 416.24758 -32.75076 90)
		(property "Reference" "C99"
			(at 0 0 90)
			(layer "F.SilkS")
			(hide yes)
			(effects
				(font
					(size 1.27 1.27)
				)
			)
		)
		(property "Value" ""
			(at 0 0 90)
			(layer "F.Fab")
			(effects
				(font
					(size 1.27 1.27)
				)
			)
		)
		(duplicate_pad_numbers_are_jumpers no)
		(fp_line
			(start 0.7874 -0.4064)
			(end 0.7874 0.4064)
			(stroke
				(width 0.1524)
				(type default)
			)
			(layer "F.SilkS")
		)
		(fp_line
			(start -0.7874 -0.4064)
			(end 0.7874 -0.4064)
			(stroke
				(width 0.1524)
				(type default)
			)
			(layer "F.SilkS")
		)
		(fp_line
			(start 0.7874 0.4064)
			(end -0.7874 0.4064)
			(stroke
				(width 0.1524)
				(type default)
			)
			(layer "F.SilkS")
		)
		(fp_line
			(start -0.7874 0.4064)
			(end -0.7874 -0.4064)
			(stroke
				(width 0.1524)
				(type default)
			)
			(layer "F.SilkS")
		)
		(fp_line
			(start -0.12065 -0.305054)
			(end -0.12065 -0.2794)
			(stroke
				(width 0.1)
				(type default)
			)
			(layer "F.Fab")
		)
		(fp_line
			(start -0.67945 -0.305054)
			(end -0.12065 -0.305054)
			(stroke
				(width 0.1)
				(type default)
			)
			(layer "F.Fab")
		)
		(fp_line
			(start 0.67945 -0.3048)
			(end 0.67945 0.3048)
			(stroke
				(width 0.1)
				(type default)
			)
			(layer "F.Fab")
		)
		(fp_line
			(start 0.12065 -0.3048)
			(end 0.67945 -0.3048)
			(stroke
				(width 0.1)
				(type default)
			)
			(layer "F.Fab")
		)
		(fp_line
			(start 0.12065 -0.2794)
			(end 0.12065 -0.3048)
			(stroke
				(width 0.1)
				(type default)
			)
			(layer "F.Fab")
		)
		(fp_line
			(start -0.12065 -0.2794)
			(end 0.12065 -0.2794)
			(stroke
				(width 0.1)
				(type default)
			)
			(layer "F.Fab")
		)
		(fp_line
			(start 0.120396 0.2794)
			(end -0.12065 0.2794)
			(stroke
				(width 0.1)
				(type default)
			)
			(layer "F.Fab")
		)
		(fp_line
			(start -0.12065 0.2794)
			(end -0.12065 0.3048)
			(stroke
				(width 0.1)
				(type default)
			)
			(layer "F.Fab")
		)
		(fp_line
			(start 0.67945 0.3048)
			(end 0.120396 0.3048)
			(stroke
				(width 0.1)
				(type default)
			)
			(layer "F.Fab")
		)
		(fp_line
			(start 0.120396 0.3048)
			(end 0.120396 0.2794)
			(stroke
				(width 0.1)
				(type default)
			)
			(layer "F.Fab")
		)
		(fp_line
			(start -0.12065 0.3048)
			(end -0.67945 0.3048)
			(stroke
				(width 0.1)
				(type default)
			)
			(layer "F.Fab")
		)
		(fp_line
			(start -0.67945 0.3048)
			(end -0.67945 -0.305054)
			(stroke
				(width 0.1)
				(type default)
			)
			(layer "F.Fab")
		)
		(pad "1" smd circle
			(at -0.40005 0 90)
			(size 0 0)
			(layers "F.Cu" "F.Mask" "F.Paste")
			(net "P12V_LED_SS")
		)
		(pad "2" smd circle
			(at 0.40005 0 90)
			(size 0 0)
			(layers "F.Cu" "F.Mask" "F.Paste")
			(net "GND")
		)
	)
	(footprint ""
		(layer "F.Cu")
		(at 388.3914 -19.939)
		(property "Reference" "H27"
			(at -0.889 3.20167 0)
			(unlocked yes)
			(layer "F.SilkS")
			(effects
				(font
					(size 0.7874 0.5842)
					(thickness 0.1524)
				)
				(justify left)
			)
		)
		(property "Value" ""
			(at 0 0 0)
			(layer "F.Fab")
			(effects
				(font
					(size 1.27 1.27)
				)
			)
		)
		(duplicate_pad_numbers_are_jumpers no)
		(fp_circle
			(center 0 0)
			(end 2.4003 0)
			(stroke
				(width 0.1524)
				(type default)
			)
			(fill no)
			(layer "F.SilkS")
		)
		(fp_circle
			(center 0 0)
			(end 6.5913 0)
			(stroke
				(width 0.1524)
				(type default)
			)
			(fill no)
			(layer "B.SilkS")
		)
		(fp_circle
			(center 0 0)
			(end 6.5913 0)
			(stroke
				(width 0.1)
				(type default)
			)
			(fill no)
			(layer "B.Fab")
		)
		(fp_circle
			(center 0 0)
			(end 2.4003 0)
			(stroke
				(width 0.1)
				(type default)
			)
			(fill no)
			(layer "F.Fab")
		)
		(pad "" np_thru_hole circle
			(at 0 0)
			(size 3.175 3.175)
			(drill 3.175)
			(layers "*.Cu" "*.Mask")
			(clearance 0.381)
			(thermal_gap 0.381)
		)
		(zone
			(layers "F.Cu" "B.Cu" "In1.Cu" "In2.Cu" "In3.Cu" "In4.Cu" "In5.Cu" "In6.Cu"
				"In7.Cu" "In8.Cu"
			)
			(hatch none 0.5)
			(connect_pads
				(clearance 0)
			)
			(min_thickness 0.25)
			(keepout
				(tracks not_allowed)
				(vias allowed)
				(pads allowed)
				(copperpour not_allowed)
				(footprints allowed)
			)
			(placement
				(enabled no)
				(sheetname "")
			)
			(fill
				(thermal_gap 0.5)
				(thermal_bridge_width 0.5)
				(island_removal_mode 0)
			)
			(polygon
				(pts
					(arc
						(start 390.4869 -19.939)
						(mid 386.2959 -19.939)
						(end 390.4869 -19.939)
					)
				)
			)
		)
	)
	(footprint ""
		(layer "F.Cu")
		(at 433.451 -34.163 180)
		(property "Reference" "R25"
			(at 0 0 180)
			(layer "F.SilkS")
			(hide yes)
			(effects
				(font
					(size 1.27 1.27)
				)
			)
		)
		(property "Value" ""
			(at 0 0 180)
			(layer "F.Fab")
			(effects
				(font
					(size 1.27 1.27)
				)
			)
		)
		(duplicate_pad_numbers_are_jumpers no)
		(fp_line
			(start 0.7874 0.4064)
			(end -0.7874 0.4064)
			(stroke
				(width 0.1524)
				(type default)
			)
			(layer "F.SilkS")
		)
		(fp_line
			(start 0.7874 -0.4064)
			(end 0.7874 0.4064)
			(stroke
				(width 0.1524)
				(type default)
			)
			(layer "F.SilkS")
		)
		(fp_line
			(start -0.7874 0.4064)
			(end -0.7874 -0.4064)
			(stroke
				(width 0.1524)
				(type default)
			)
			(layer "F.SilkS")
		)
		(fp_line
			(start -0.7874 -0.4064)
			(end 0.7874 -0.4064)
			(stroke
				(width 0.1524)
				(type default)
			)
			(layer "F.SilkS")
		)
		(fp_line
			(start 0.67945 0.3048)
			(end 0.120396 0.3048)
			(stroke
				(width 0.1)
				(type default)
			)
			(layer "F.Fab")
		)
		(fp_line
			(start 0.67945 -0.3048)
			(end 0.67945 0.3048)
			(stroke
				(width 0.1)
				(type default)
			)
			(layer "F.Fab")
		)
		(fp_line
			(start 0.12065 -0.2794)
			(end 0.12065 -0.3048)
			(stroke
				(width 0.1)
				(type default)
			)
			(layer "F.Fab")
		)
		(fp_line
			(start 0.12065 -0.3048)
			(end 0.67945 -0.3048)
			(stroke
				(width 0.1)
				(type default)
			)
			(layer "F.Fab")
		)
		(fp_line
			(start 0.120396 0.3048)
			(end 0.120396 0.2794)
			(stroke
				(width 0.1)
				(type default)
			)
			(layer "F.Fab")
		)
		(fp_line
			(start 0.120396 0.2794)
			(end -0.12065 0.2794)
			(stroke
				(width 0.1)
				(type default)
			)
			(layer "F.Fab")
		)
		(fp_line
			(start -0.12065 0.3048)
			(end -0.67945 0.3048)
			(stroke
				(width 0.1)
				(type default)
			)
			(layer "F.Fab")
		)
		(fp_line
			(start -0.12065 0.2794)
			(end -0.12065 0.3048)
			(stroke
				(width 0.1)
				(type default)
			)
			(layer "F.Fab")
		)
		(fp_line
			(start -0.12065 -0.2794)
			(end 0.12065 -0.2794)
			(stroke
				(width 0.1)
				(type default)
			)
			(layer "F.Fab")
		)
		(fp_line
			(start -0.12065 -0.305054)
			(end -0.12065 -0.2794)
			(stroke
				(width 0.1)
				(type default)
			)
			(layer "F.Fab")
		)
		(fp_line
			(start -0.67945 0.3048)
			(end -0.67945 -0.305054)
			(stroke
				(width 0.1)
				(type default)
			)
			(layer "F.Fab")
		)
		(fp_line
			(start -0.67945 -0.305054)
			(end -0.12065 -0.305054)
			(stroke
				(width 0.1)
				(type default)
			)
			(layer "F.Fab")
		)
		(pad "1" smd circle
			(at -0.40005 0 180)
			(size 0 0)
			(layers "F.Cu" "F.Mask" "F.Paste")
			(net "PD_9543_FAN_A0")
		)
		(pad "2" smd circle
			(at 0.40005 0 180)
			(size 0 0)
			(layers "F.Cu" "F.Mask" "F.Paste")
			(net "GND")
		)
	)
	(footprint ""
		(layer "F.Cu")
		(at 278.6634 -75.184)
		(property "Reference" "PR31"
			(at 0 0 0)
			(layer "F.SilkS")
			(hide yes)
			(effects
				(font
					(size 1.27 1.27)
				)
			)
		)
		(property "Value" ""
			(at 0 0 0)
			(layer "F.Fab")
			(effects
				(font
					(size 1.27 1.27)
				)
			)
		)
		(duplicate_pad_numbers_are_jumpers no)
		(fp_line
			(start -0.7874 -0.4064)
			(end 0.7874 -0.4064)
			(stroke
				(width 0.1524)
				(type default)
			)
			(layer "F.SilkS")
		)
		(fp_line
			(start -0.7874 0.4064)
			(end -0.7874 -0.4064)
			(stroke
				(width 0.1524)
				(type default)
			)
			(layer "F.SilkS")
		)
		(fp_line
			(start 0.7874 -0.4064)
			(end 0.7874 0.4064)
			(stroke
				(width 0.1524)
				(type default)
			)
			(layer "F.SilkS")
		)
		(fp_line
			(start 0.7874 0.4064)
			(end -0.7874 0.4064)
			(stroke
				(width 0.1524)
				(type default)
			)
			(layer "F.SilkS")
		)
		(fp_line
			(start -0.67945 -0.305054)
			(end -0.12065 -0.305054)
			(stroke
				(width 0.1)
				(type default)
			)
			(layer "F.Fab")
		)
		(fp_line
			(start -0.67945 0.3048)
			(end -0.67945 -0.305054)
			(stroke
				(width 0.1)
				(type default)
			)
			(layer "F.Fab")
		)
		(fp_line
			(start -0.12065 -0.305054)
			(end -0.12065 -0.2794)
			(stroke
				(width 0.1)
				(type default)
			)
			(layer "F.Fab")
		)
		(fp_line
			(start -0.12065 -0.2794)
			(end 0.12065 -0.2794)
			(stroke
				(width 0.1)
				(type default)
			)
			(layer "F.Fab")
		)
		(fp_line
			(start -0.12065 0.2794)
			(end -0.12065 0.3048)
			(stroke
				(width 0.1)
				(type default)
			)
			(layer "F.Fab")
		)
		(fp_line
			(start -0.12065 0.3048)
			(end -0.67945 0.3048)
			(stroke
				(width 0.1)
				(type default)
			)
			(layer "F.Fab")
		)
		(fp_line
			(start 0.120396 0.2794)
			(end -0.12065 0.2794)
			(stroke
				(width 0.1)
				(type default)
			)
			(layer "F.Fab")
		)
		(fp_line
			(start 0.120396 0.3048)
			(end 0.120396 0.2794)
			(stroke
				(width 0.1)
				(type default)
			)
			(layer "F.Fab")
		)
		(fp_line
			(start 0.12065 -0.3048)
			(end 0.67945 -0.3048)
			(stroke
				(width 0.1)
				(type default)
			)
			(layer "F.Fab")
		)
		(fp_line
			(start 0.12065 -0.2794)
			(end 0.12065 -0.3048)
			(stroke
				(width 0.1)
				(type default)
			)
			(layer "F.Fab")
		)
		(fp_line
			(start 0.67945 -0.3048)
			(end 0.67945 0.3048)
			(stroke
				(width 0.1)
				(type default)
			)
			(layer "F.Fab")
		)
		(fp_line
			(start 0.67945 0.3048)
			(end 0.120396 0.3048)
			(stroke
				(width 0.1)
				(type default)
			)
			(layer "F.Fab")
		)
		(pad "1" smd circle
			(at -0.40005 0)
			(size 0 0)
			(layers "F.Cu" "F.Mask" "F.Paste")
			(net "P52V_HS1_EFAULT_R")
		)
		(pad "2" smd circle
			(at 0.40005 0)
			(size 0 0)
			(layers "F.Cu" "F.Mask" "F.Paste")
			(net "P52V_HS1_EFAULT")
		)
	)
)
